#ISCELL
  logical_power design_note *
  *
#ISCELL
  pure_quanta quanta_title_block_c *
  *
#ISCELL
  standard tap *
  page32_i101
#ISCELL
  standard tap *
  page32_i102
#ISCELL
  standard tap *
  page32_i103
#ISCELL
  standard tap *
  page32_i104
#ISCELL
  standard tap *
  page32_i106
#ISCELL
  standard tap *
  page32_i107
#ISCELL
  standard tap *
  page32_i108
#ISCELL
  standard tap *
  page32_i109
#ISCELL
  standard tap *
  page32_i110
#ISCELL
  standard tap *
  page32_i111
#ISCELL
  standard tap *
  page32_i112
#ISCELL
  standard tap *
  page32_i113
#ISCELL
  standard tap *
  page32_i114
#ISCELL
  standard tap *
  page32_i115
#ISCELL
  standard tap *
  page32_i116
#ISCELL
  standard tap *
  page32_i117
#ISCELL
  standard tap *
  page32_i118
#ISCELL
  standard tap *
  page32_i119
#ISCELL
  standard tap *
  page32_i120
#ISCELL
  standard tap *
  page32_i121
#ISCELL
  standard tap *
  page32_i122
#ISCELL
  standard tap *
  page32_i123
#ISCELL
  standard tap *
  page32_i124
#ISCELL
  standard tap *
  page32_i125
#ISCELL
  standard tap *
  page32_i126
#ISCELL
  standard tap *
  page32_i127
#ISCELL
  standard tap *
  page32_i128
#ISCELL
  standard tap *
  page32_i129
#ISCELL
  standard tap *
  page32_i130
#ISCELL
  standard tap *
  page32_i131
#ISCELL
  standard tap *
  page32_i132
#ISCELL
  standard tap *
  page32_i133
#ISCELL
  standard tap *
  page32_i134
#ISCELL
  standard tap *
  page32_i135
#ISCELL
  standard tap *
  page32_i136
#ISCELL
  standard tap *
  page32_i137
#ISCELL
  standard tap *
  page32_i139
#ISCELL
  standard tap *
  page32_i140
#ISCELL
  standard tap *
  page32_i141
#ISCELL
  standard tap *
  page32_i142
#ISCELL
  standard tap *
  page32_i143
#ISCELL
  standard tap *
  page32_i144
#ISCELL
  standard offpage *
  page32_i145
#ISCELL
  standard tap *
  page32_i146
#ISCELL
  standard tap *
  page32_i147
#ISCELL
  standard tap *
  page32_i148
#ISCELL
  standard tap *
  page32_i149
#ISCELL
  standard tap *
  page32_i150
#ISCELL
  standard tap *
  page32_i151
#ISCELL
  standard tap *
  page32_i152
#ISCELL
  standard tap *
  page32_i153
#ISCELL
  standard tap *
  page32_i154
#ISCELL
  standard tap *
  page32_i155
#ISCELL
  standard tap *
  page32_i156
#ISCELL
  standard tap *
  page32_i157
#ISCELL
  standard tap *
  page32_i158
#ISCELL
  standard tap *
  page32_i159
#ISCELL
  standard tap *
  page32_i160
#ISCELL
  standard tap *
  page32_i161
#ISCELL
  standard tap *
  page32_i162
#ISCELL
  standard tap *
  page32_i163
#ISCELL
  standard offpage *
  page32_i164
#ISCELL
  standard tap *
  page32_i165
#ISCELL
  standard tap *
  page32_i166
#ISCELL
  standard tap *
  page32_i167
#ISCELL
  standard tap *
  page32_i168
#ISCELL
  standard tap *
  page32_i169
#ISCELL
  standard tap *
  page32_i170
#ISCELL
  standard tap *
  page32_i171
#ISCELL
  standard tap *
  page32_i172
#ISCELL
  standard tap *
  page32_i173
#ISCELL
  standard tap *
  page32_i174
#ISCELL
  standard tap *
  page32_i175
#ISCELL
  standard tap *
  page32_i176
#ISCELL
  standard tap *
  page32_i19
#ISCELL
  standard offpage *
  page32_i2
#ISCELL
  standard tap *
  page32_i21
#ISCELL
  standard tap *
  page32_i34
#ISCELL
  standard tap *
  page32_i52
#ISCELL
  standard tap *
  page32_i53
#ISCELL
  standard tap *
  page32_i54
#ISCELL
  standard tap *
  page32_i55
#ISCELL
  standard tap *
  page32_i58
#ISCELL
  standard tap *
  page32_i59
#ISCELL
  standard tap *
  page32_i61
#ISCELL
  standard tap *
  page32_i62
#ISCELL
  standard tap *
  page32_i64
#ISCELL
  standard tap *
  page32_i66
#ISCELL
  standard offpage *
  page32_i69
#CELL
  pure_quanta socket4677_azif0045p001c01cs *
  page32_i70
#ISCELL
  standard tap *
  page32_i77
#ISCELL
  standard tap *
  page32_i78
#ISCELL
  standard tap *
  page32_i79
#ISCELL
  standard tap *
  page32_i80
#ISCELL
  standard tap *
  page32_i82
#ISCELL
  standard tap *
  page32_i84
#ISCELL
  standard tap *
  page32_i85
#ISCELL
  standard tap *
  page32_i86
#ISCELL
  standard tap *
  page32_i95
#ISCELL
  standard tap *
  page32_i97
#ISCELL
  standard tap *
  page32_i98
